(kicad_pcb
	(version 20260206)
	(generator "pcbnew")
	(generator_version "10.0")
	(general
		(thickness 1.6)
		(legacy_teardrops no)
	)
	(paper "A4")
	(title_block
		(title "01162023_DA0F0TEBIF0_F0T_Expander_BD_F_brd_V02_OCP.brd")
		(comment 1 "Grand Teton / footprints 4242-4248 of 9728")
	)
	(layers
		(0 "F.Cu" signal "TOP")
		(4 "In1.Cu" signal "GND")
		(6 "In2.Cu" signal "VCC")
		(8 "In3.Cu" signal "VCC1")
		(10 "In4.Cu" signal "GND1")
		(12 "In5.Cu" signal "IN1")
		(14 "In6.Cu" signal "GND2")
		(16 "In7.Cu" signal "IN2")
		(18 "In8.Cu" signal "GND3")
		(20 "In9.Cu" signal "IN3")
		(22 "In10.Cu" signal "GND4")
		(24 "In11.Cu" signal "IN4")
		(26 "In12.Cu" signal "GND5")
		(28 "In13.Cu" signal "IN5")
		(30 "In14.Cu" signal "GND6")
		(32 "In15.Cu" signal "IN6")
		(34 "In16.Cu" signal "GND7")
		(2 "B.Cu" signal "BOTTOM")
		(9 "F.Adhes" user "F.Adhesive")
		(11 "B.Adhes" user "B.Adhesive")
		(13 "F.Paste" user "Package Geometry/Pastemask Top")
		(15 "B.Paste" user "Package Geometry/Pastemask Bottom")
		(5 "F.SilkS" user "Ref Des/Silkscreen Top")
		(7 "B.SilkS" user "Ref Des/Silkscreen Bottom")
		(1 "F.Mask" user "Board Geometry/Soldermask Top")
		(3 "B.Mask" user "Board Geometry/Soldermask Bottom")
		(17 "Dwgs.User" user "User.Drawings")
		(19 "Cmts.User" user "User.Comments")
		(21 "Eco1.User" user "User.Eco1")
		(23 "Eco2.User" user "User.Eco2")
		(25 "Edge.Cuts" user "Board Geometry/Outline")
		(27 "Margin" user)
		(31 "F.CrtYd" user "Package Geometry/Place Bound Top")
		(29 "B.CrtYd" user "Package Geometry/Place Bound Bottom")
		(35 "F.Fab" user "Ref Des/Assembly Top")
		(33 "B.Fab" user "Ref Des/Assembly Bottom")
	)
	(footprint ""
		(layer "F.Cu")
		(at 167.711628 -71.458074 -90)
		(property "Reference" "PD101"
			(at 4.198874 -2.825242 90)
			(unlocked yes)
			(layer "F.SilkS")
			(effects
				(font
					(size 0.7874 0.5842)
					(thickness 0.1524)
				)
				(justify left)
			)
		)
		(property "Value" ""
			(at 0 0 270)
			(layer "F.Fab")
			(effects
				(font
					(size 1.27 1.27)
				)
			)
		)
		(duplicate_pad_numbers_are_jumpers no)
		(fp_line
			(start -3.656584 1.970024)
			(end 4.240784 1.970024)
			(stroke
				(width 0.1524)
				(type default)
			)
			(layer "F.SilkS")
		)
		(fp_line
			(start 4.240784 1.970024)
			(end 4.240784 -1.970024)
			(stroke
				(width 0.1524)
				(type default)
			)
			(layer "F.SilkS")
		)
		(fp_line
			(start -3.656584 -1.970024)
			(end -3.656584 1.970024)
			(stroke
				(width 0.1524)
				(type default)
			)
			(layer "F.SilkS")
		)
		(fp_line
			(start 4.240784 -1.970024)
			(end -3.656584 -1.970024)
			(stroke
				(width 0.1524)
				(type default)
			)
			(layer "F.SilkS")
		)
		(fp_poly
			(pts
				(xy 3.580384 1.970024) (xy 3.580384 -1.970024) (xy 4.240784 -1.970024) (xy 4.240784 1.970024)
			)
			(stroke
				(width 0)
				(type default)
			)
			(fill yes)
			(layer "F.SilkS")
		)
		(fp_line
			(start -2.3749 1.970024)
			(end 2.3749 1.970024)
			(stroke
				(width 0.1)
				(type default)
			)
			(layer "F.Fab")
		)
		(fp_line
			(start 2.3749 1.970024)
			(end 2.3749 -1.970024)
			(stroke
				(width 0.1)
				(type default)
			)
			(layer "F.Fab")
		)
		(fp_line
			(start -2.3749 -1.970024)
			(end -2.3749 1.970024)
			(stroke
				(width 0.1)
				(type default)
			)
			(layer "F.Fab")
		)
		(fp_line
			(start 2.3749 -1.970024)
			(end -2.3749 -1.970024)
			(stroke
				(width 0.1)
				(type default)
			)
			(layer "F.Fab")
		)
		(fp_text user "+"
			(at -4.9784 -0.23495 270)
			(unlocked yes)
			(layer "F.Fab")
			(effects
				(font
					(size 1.905 1.4224)
					(thickness 0.1524)
				)
				(justify left)
			)
		)
		(fp_text user "-"
			(at 4.1656 -0.23495 270)
			(unlocked yes)
			(layer "F.Fab")
			(effects
				(font
					(size 1.905 1.4224)
					(thickness 0.1524)
				)
				(justify left)
			)
		)
		(pad "A" smd rect
			(at -2.450084 0 270)
			(size 2.159 2.2606)
			(layers "F.Cu" "F.Mask" "F.Paste")
			(net "GND")
		)
		(pad "C" smd rect
			(at 2.450084 0 270)
			(size 2.159 2.2606)
			(layers "F.Cu" "F.Mask" "F.Paste")
			(net "P12V_AUX")
		)
	)
	(footprint ""
		(layer "F.Cu")
		(at 396.209266 -80.356202 180)
		(property "Reference" "R1754"
			(at 0 0 180)
			(layer "F.SilkS")
			(hide yes)
			(effects
				(font
					(size 1.27 1.27)
				)
			)
		)
		(property "Value" ""
			(at 0 0 180)
			(layer "F.Fab")
			(effects
				(font
					(size 1.27 1.27)
				)
			)
		)
		(duplicate_pad_numbers_are_jumpers no)
		(fp_line
			(start 0.7874 0.4064)
			(end -0.7874 0.4064)
			(stroke
				(width 0.1524)
				(type default)
			)
			(layer "F.SilkS")
		)
		(fp_line
			(start 0.7874 -0.4064)
			(end 0.7874 0.4064)
			(stroke
				(width 0.1524)
				(type default)
			)
			(layer "F.SilkS")
		)
		(fp_line
			(start -0.7874 0.4064)
			(end -0.7874 -0.4064)
			(stroke
				(width 0.1524)
				(type default)
			)
			(layer "F.SilkS")
		)
		(fp_line
			(start -0.7874 -0.4064)
			(end 0.7874 -0.4064)
			(stroke
				(width 0.1524)
				(type default)
			)
			(layer "F.SilkS")
		)
		(fp_line
			(start 0.67945 0.3048)
			(end 0.120396 0.3048)
			(stroke
				(width 0.1)
				(type default)
			)
			(layer "F.Fab")
		)
		(fp_line
			(start 0.67945 -0.3048)
			(end 0.67945 0.3048)
			(stroke
				(width 0.1)
				(type default)
			)
			(layer "F.Fab")
		)
		(fp_line
			(start 0.12065 -0.2794)
			(end 0.12065 -0.3048)
			(stroke
				(width 0.1)
				(type default)
			)
			(layer "F.Fab")
		)
		(fp_line
			(start 0.12065 -0.3048)
			(end 0.67945 -0.3048)
			(stroke
				(width 0.1)
				(type default)
			)
			(layer "F.Fab")
		)
		(fp_line
			(start 0.120396 0.3048)
			(end 0.120396 0.2794)
			(stroke
				(width 0.1)
				(type default)
			)
			(layer "F.Fab")
		)
		(fp_line
			(start 0.120396 0.2794)
			(end -0.12065 0.2794)
			(stroke
				(width 0.1)
				(type default)
			)
			(layer "F.Fab")
		)
		(fp_line
			(start -0.12065 0.3048)
			(end -0.67945 0.3048)
			(stroke
				(width 0.1)
				(type default)
			)
			(layer "F.Fab")
		)
		(fp_line
			(start -0.12065 0.2794)
			(end -0.12065 0.3048)
			(stroke
				(width 0.1)
				(type default)
			)
			(layer "F.Fab")
		)
		(fp_line
			(start -0.12065 -0.2794)
			(end 0.12065 -0.2794)
			(stroke
				(width 0.1)
				(type default)
			)
			(layer "F.Fab")
		)
		(fp_line
			(start -0.12065 -0.305054)
			(end -0.12065 -0.2794)
			(stroke
				(width 0.1)
				(type default)
			)
			(layer "F.Fab")
		)
		(fp_line
			(start -0.67945 0.3048)
			(end -0.67945 -0.305054)
			(stroke
				(width 0.1)
				(type default)
			)
			(layer "F.Fab")
		)
		(fp_line
			(start -0.67945 -0.305054)
			(end -0.12065 -0.305054)
			(stroke
				(width 0.1)
				(type default)
			)
			(layer "F.Fab")
		)
		(pad "1" smd circle
			(at -0.40005 0 180)
			(size 0 0)
			(layers "F.Cu" "F.Mask" "F.Paste")
			(net "P3V3_AUX")
		)
		(pad "2" smd circle
			(at 0.40005 0 180)
			(size 0 0)
			(layers "F.Cu" "F.Mask" "F.Paste")
			(net "SMB_BIC_I2C6_MUX_SSD_8_15_ADC_R_SDA")
		)
	)
	(footprint ""
		(layer "F.Cu")
		(at 74.697082 -350.098614 90)
		(property "Reference" "C116"
			(at 0 0 90)
			(layer "F.SilkS")
			(hide yes)
			(effects
				(font
					(size 1.27 1.27)
				)
			)
		)
		(property "Value" ""
			(at 0 0 90)
			(layer "F.Fab")
			(effects
				(font
					(size 1.27 1.27)
				)
			)
		)
		(duplicate_pad_numbers_are_jumpers no)
		(fp_line
			(start 0.299974 -0.150114)
			(end 0.299974 0.150114)
			(stroke
				(width 0.1)
				(type default)
			)
			(layer "F.Fab")
		)
		(fp_line
			(start -0.299974 -0.150114)
			(end 0.299974 -0.150114)
			(stroke
				(width 0.1)
				(type default)
			)
			(layer "F.Fab")
		)
		(fp_line
			(start 0.299974 0.150114)
			(end -0.299974 0.150114)
			(stroke
				(width 0.1)
				(type default)
			)
			(layer "F.Fab")
		)
		(fp_line
			(start -0.299974 0.150114)
			(end -0.299974 -0.150114)
			(stroke
				(width 0.1)
				(type default)
			)
			(layer "F.Fab")
		)
		(pad "1" smd rect
			(at -0.2667 0 90)
			(size 0.3048 0.381)
			(layers "F.Cu" "F.Mask" "F.Paste")
			(net "P5E_PEX0_STN5_TX_DN<86>")
		)
		(pad "2" smd rect
			(at 0.2667 0 90)
			(size 0.3048 0.381)
			(layers "F.Cu" "F.Mask" "F.Paste")
			(net "P5E_PEX0_STN5_TX_C_DN<86>")
		)
	)
	(footprint ""
		(layer "F.Cu")
		(at 357.746808 -152.859994 180)
		(property "Reference" "PR7047"
			(at 0 0 180)
			(layer "F.SilkS")
			(hide yes)
			(effects
				(font
					(size 1.27 1.27)
				)
			)
		)
		(property "Value" ""
			(at 0 0 180)
			(layer "F.Fab")
			(effects
				(font
					(size 1.27 1.27)
				)
			)
		)
		(duplicate_pad_numbers_are_jumpers no)
		(fp_line
			(start 1.2954 0.5842)
			(end -1.2954 0.5842)
			(stroke
				(width 0.1524)
				(type default)
			)
			(layer "F.SilkS")
		)
		(fp_line
			(start 1.2954 -0.5842)
			(end 1.2954 0.5842)
			(stroke
				(width 0.1524)
				(type default)
			)
			(layer "F.SilkS")
		)
		(fp_line
			(start -1.2954 0.5842)
			(end -1.2954 -0.5842)
			(stroke
				(width 0.1524)
				(type default)
			)
			(layer "F.SilkS")
		)
		(fp_line
			(start -1.2954 -0.5842)
			(end 1.2954 -0.5842)
			(stroke
				(width 0.1524)
				(type default)
			)
			(layer "F.SilkS")
		)
		(fp_line
			(start 1.1938 0.4064)
			(end 0.8636 0.4064)
			(stroke
				(width 0.1)
				(type default)
			)
			(layer "F.Fab")
		)
		(fp_line
			(start 1.1938 -0.406654)
			(end 1.1938 0.4064)
			(stroke
				(width 0.1)
				(type default)
			)
			(layer "F.Fab")
		)
		(fp_line
			(start 0.8636 0.4572)
			(end -0.8636 0.4572)
			(stroke
				(width 0.1)
				(type default)
			)
			(layer "F.Fab")
		)
		(fp_line
			(start 0.8636 0.4064)
			(end 0.8636 0.4572)
			(stroke
				(width 0.1)
				(type default)
			)
			(layer "F.Fab")
		)
		(fp_line
			(start 0.8636 -0.406654)
			(end 1.1938 -0.406654)
			(stroke
				(width 0.1)
				(type default)
			)
			(layer "F.Fab")
		)
		(fp_line
			(start 0.8636 -0.4572)
			(end 0.8636 -0.406654)
			(stroke
				(width 0.1)
				(type default)
			)
			(layer "F.Fab")
		)
		(fp_line
			(start -0.8636 0.4572)
			(end -0.8636 0.4318)
			(stroke
				(width 0.1)
				(type default)
			)
			(layer "F.Fab")
		)
		(fp_line
			(start -0.8636 0.4318)
			(end -0.8636 0.4064)
			(stroke
				(width 0.1)
				(type default)
			)
			(layer "F.Fab")
		)
		(fp_line
			(start -0.8636 0.4064)
			(end -1.1938 0.4064)
			(stroke
				(width 0.1)
				(type default)
			)
			(layer "F.Fab")
		)
		(fp_line
			(start -0.8636 -0.406654)
			(end -0.8636 -0.4572)
			(stroke
				(width 0.1)
				(type default)
			)
			(layer "F.Fab")
		)
		(fp_line
			(start -0.8636 -0.4572)
			(end 0.8636 -0.4572)
			(stroke
				(width 0.1)
				(type default)
			)
			(layer "F.Fab")
		)
		(fp_line
			(start -1.1938 0.4064)
			(end -1.1938 -0.406654)
			(stroke
				(width 0.1)
				(type default)
			)
			(layer "F.Fab")
		)
		(fp_line
			(start -1.1938 -0.406654)
			(end -0.8636 -0.406654)
			(stroke
				(width 0.1)
				(type default)
			)
			(layer "F.Fab")
		)
		(pad "1" smd rect
			(at -0.7366 0 90)
			(size 0.7112 0.8128)
			(layers "F.Cu" "F.Mask" "F.Paste")
			(net "P12V_NIC6_CO_AVIN_PD")
		)
		(pad "2" smd rect
			(at 0.7366 0 90)
			(size 0.7112 0.8128)
			(layers "F.Cu" "F.Mask" "F.Paste")
			(net "P12V_AUX")
		)
	)
	(footprint ""
		(layer "F.Cu")
		(at 215.075516 -117.191028)
		(property "Reference" "PC494"
			(at 0 0 0)
			(layer "F.SilkS")
			(hide yes)
			(effects
				(font
					(size 1.27 1.27)
				)
			)
		)
		(property "Value" ""
			(at 0 0 0)
			(layer "F.Fab")
			(effects
				(font
					(size 1.27 1.27)
				)
			)
		)
		(duplicate_pad_numbers_are_jumpers no)
		(fp_line
			(start -0.7874 -0.4064)
			(end 0.7874 -0.4064)
			(stroke
				(width 0.1524)
				(type default)
			)
			(layer "F.SilkS")
		)
		(fp_line
			(start -0.7874 0.4064)
			(end -0.7874 -0.4064)
			(stroke
				(width 0.1524)
				(type default)
			)
			(layer "F.SilkS")
		)
		(fp_line
			(start 0.7874 -0.4064)
			(end 0.7874 0.4064)
			(stroke
				(width 0.1524)
				(type default)
			)
			(layer "F.SilkS")
		)
		(fp_line
			(start 0.7874 0.4064)
			(end -0.7874 0.4064)
			(stroke
				(width 0.1524)
				(type default)
			)
			(layer "F.SilkS")
		)
		(fp_line
			(start -0.67945 -0.305054)
			(end -0.12065 -0.305054)
			(stroke
				(width 0.1)
				(type default)
			)
			(layer "F.Fab")
		)
		(fp_line
			(start -0.67945 0.3048)
			(end -0.67945 -0.305054)
			(stroke
				(width 0.1)
				(type default)
			)
			(layer "F.Fab")
		)
		(fp_line
			(start -0.12065 -0.305054)
			(end -0.12065 -0.2794)
			(stroke
				(width 0.1)
				(type default)
			)
			(layer "F.Fab")
		)
		(fp_line
			(start -0.12065 -0.2794)
			(end 0.12065 -0.2794)
			(stroke
				(width 0.1)
				(type default)
			)
			(layer "F.Fab")
		)
		(fp_line
			(start -0.12065 0.2794)
			(end -0.12065 0.3048)
			(stroke
				(width 0.1)
				(type default)
			)
			(layer "F.Fab")
		)
		(fp_line
			(start -0.12065 0.3048)
			(end -0.67945 0.3048)
			(stroke
				(width 0.1)
				(type default)
			)
			(layer "F.Fab")
		)
		(fp_line
			(start 0.120396 0.2794)
			(end -0.12065 0.2794)
			(stroke
				(width 0.1)
				(type default)
			)
			(layer "F.Fab")
		)
		(fp_line
			(start 0.120396 0.3048)
			(end 0.120396 0.2794)
			(stroke
				(width 0.1)
				(type default)
			)
			(layer "F.Fab")
		)
		(fp_line
			(start 0.12065 -0.3048)
			(end 0.67945 -0.3048)
			(stroke
				(width 0.1)
				(type default)
			)
			(layer "F.Fab")
		)
		(fp_line
			(start 0.12065 -0.2794)
			(end 0.12065 -0.3048)
			(stroke
				(width 0.1)
				(type default)
			)
			(layer "F.Fab")
		)
		(fp_line
			(start 0.67945 -0.3048)
			(end 0.67945 0.3048)
			(stroke
				(width 0.1)
				(type default)
			)
			(layer "F.Fab")
		)
		(fp_line
			(start 0.67945 0.3048)
			(end 0.120396 0.3048)
			(stroke
				(width 0.1)
				(type default)
			)
			(layer "F.Fab")
		)
		(pad "1" smd circle
			(at -0.40005 0)
			(size 0 0)
			(layers "F.Cu" "F.Mask" "F.Paste")
			(net "P3V3_NIC3_SS")
		)
		(pad "2" smd circle
			(at 0.40005 0)
			(size 0 0)
			(layers "F.Cu" "F.Mask" "F.Paste")
			(net "GND")
		)
	)
	(footprint ""
		(layer "F.Cu")
		(at 197.972172 -32.848042 90)
		(property "Reference" "PC932"
			(at 0 0 90)
			(layer "F.SilkS")
			(hide yes)
			(effects
				(font
					(size 1.27 1.27)
				)
			)
		)
		(property "Value" ""
			(at 0 0 90)
			(layer "F.Fab")
			(effects
				(font
					(size 1.27 1.27)
				)
			)
		)
		(duplicate_pad_numbers_are_jumpers no)
		(fp_line
			(start 0.7874 -0.4064)
			(end 0.7874 0.4064)
			(stroke
				(width 0.1524)
				(type default)
			)
			(layer "F.SilkS")
		)
		(fp_line
			(start -0.7874 -0.4064)
			(end 0.7874 -0.4064)
			(stroke
				(width 0.1524)
				(type default)
			)
			(layer "F.SilkS")
		)
		(fp_line
			(start 0.7874 0.4064)
			(end -0.7874 0.4064)
			(stroke
				(width 0.1524)
				(type default)
			)
			(layer "F.SilkS")
		)
		(fp_line
			(start -0.7874 0.4064)
			(end -0.7874 -0.4064)
			(stroke
				(width 0.1524)
				(type default)
			)
			(layer "F.SilkS")
		)
		(fp_line
			(start -0.12065 -0.305054)
			(end -0.12065 -0.2794)
			(stroke
				(width 0.1)
				(type default)
			)
			(layer "F.Fab")
		)
		(fp_line
			(start -0.67945 -0.305054)
			(end -0.12065 -0.305054)
			(stroke
				(width 0.1)
				(type default)
			)
			(layer "F.Fab")
		)
		(fp_line
			(start 0.67945 -0.3048)
			(end 0.67945 0.3048)
			(stroke
				(width 0.1)
				(type default)
			)
			(layer "F.Fab")
		)
		(fp_line
			(start 0.12065 -0.3048)
			(end 0.67945 -0.3048)
			(stroke
				(width 0.1)
				(type default)
			)
			(layer "F.Fab")
		)
		(fp_line
			(start 0.12065 -0.2794)
			(end 0.12065 -0.3048)
			(stroke
				(width 0.1)
				(type default)
			)
			(layer "F.Fab")
		)
		(fp_line
			(start -0.12065 -0.2794)
			(end 0.12065 -0.2794)
			(stroke
				(width 0.1)
				(type default)
			)
			(layer "F.Fab")
		)
		(fp_line
			(start 0.120396 0.2794)
			(end -0.12065 0.2794)
			(stroke
				(width 0.1)
				(type default)
			)
			(layer "F.Fab")
		)
		(fp_line
			(start -0.12065 0.2794)
			(end -0.12065 0.3048)
			(stroke
				(width 0.1)
				(type default)
			)
			(layer "F.Fab")
		)
		(fp_line
			(start 0.67945 0.3048)
			(end 0.120396 0.3048)
			(stroke
				(width 0.1)
				(type default)
			)
			(layer "F.Fab")
		)
		(fp_line
			(start 0.120396 0.3048)
			(end 0.120396 0.2794)
			(stroke
				(width 0.1)
				(type default)
			)
			(layer "F.Fab")
		)
		(fp_line
			(start -0.12065 0.3048)
			(end -0.67945 0.3048)
			(stroke
				(width 0.1)
				(type default)
			)
			(layer "F.Fab")
		)
		(fp_line
			(start -0.67945 0.3048)
			(end -0.67945 -0.305054)
			(stroke
				(width 0.1)
				(type default)
			)
			(layer "F.Fab")
		)
		(pad "1" smd circle
			(at -0.40005 0 90)
			(size 0 0)
			(layers "F.Cu" "F.Mask" "F.Paste")
			(net "P3V3_SSD7_CO_GATE")
		)
		(pad "2" smd circle
			(at 0.40005 0 90)
			(size 0 0)
			(layers "F.Cu" "F.Mask" "F.Paste")
			(net "GND")
		)
	)
	(footprint ""
		(layer "F.Cu")
		(at 140.074142 -181.993286 180)
		(property "Reference" "R1107"
			(at 0 0 180)
			(layer "F.SilkS")
			(hide yes)
			(effects
				(font
					(size 1.27 1.27)
				)
			)
		)
		(property "Value" ""
			(at 0 0 180)
			(layer "F.Fab")
			(effects
				(font
					(size 1.27 1.27)
				)
			)
		)
		(duplicate_pad_numbers_are_jumpers no)
		(fp_line
			(start -0.7874 -0.4064)
			(end 0.7874 -0.4064)
			(stroke
				(width 0.1524)
				(type default)
			)
			(layer "F.SilkS")
		)
		(fp_line
			(start 0.67945 0.3048)
			(end 0.120396 0.3048)
			(stroke
				(width 0.1)
				(type default)
			)
			(layer "F.Fab")
		)
		(fp_line
			(start 0.67945 -0.3048)
			(end 0.67945 0.3048)
			(stroke
				(width 0.1)
				(type default)
			)
			(layer "F.Fab")
		)
		(fp_line
			(start 0.12065 -0.2794)
			(end 0.12065 -0.3048)
			(stroke
				(width 0.1)
				(type default)
			)
			(layer "F.Fab")
		)
		(fp_line
			(start 0.12065 -0.3048)
			(end 0.67945 -0.3048)
			(stroke
				(width 0.1)
				(type default)
			)
			(layer "F.Fab")
		)
		(fp_line
			(start 0.120396 0.3048)
			(end 0.120396 0.2794)
			(stroke
				(width 0.1)
				(type default)
			)
			(layer "F.Fab")
		)
		(fp_line
			(start 0.120396 0.2794)
			(end -0.12065 0.2794)
			(stroke
				(width 0.1)
				(type default)
			)
			(layer "F.Fab")
		)
		(fp_line
			(start -0.12065 0.3048)
			(end -0.67945 0.3048)
			(stroke
				(width 0.1)
				(type default)
			)
			(layer "F.Fab")
		)
		(fp_line
			(start -0.12065 0.2794)
			(end -0.12065 0.3048)
			(stroke
				(width 0.1)
				(type default)
			)
			(layer "F.Fab")
		)
		(fp_line
			(start -0.12065 -0.2794)
			(end 0.12065 -0.2794)
			(stroke
				(width 0.1)
				(type default)
			)
			(layer "F.Fab")
		)
		(fp_line
			(start -0.12065 -0.305054)
			(end -0.12065 -0.2794)
			(stroke
				(width 0.1)
				(type default)
			)
			(layer "F.Fab")
		)
		(fp_line
			(start -0.67945 0.3048)
			(end -0.67945 -0.305054)
			(stroke
				(width 0.1)
				(type default)
			)
			(layer "F.Fab")
		)
		(fp_line
			(start -0.67945 -0.305054)
			(end -0.12065 -0.305054)
			(stroke
				(width 0.1)
				(type default)
			)
			(layer "F.Fab")
		)
		(pad "1" smd circle
			(at -0.40005 0 180)
			(size 0 0)
			(layers "F.Cu" "F.Mask" "F.Paste")
			(net "CLK_100M_DB2000QL_NIC6_R_DP")
		)
		(pad "2" smd circle
			(at 0.40005 0 180)
			(size 0 0)
			(layers "F.Cu" "F.Mask" "F.Paste")
			(net "CLK_100M_DB2000QL_NIC6_DP")
		)
	)
)
